(kicad_pcb
	(version 20260206)
	(generator "pcbnew")
	(generator_version "10.0")
	(general
		(thickness 1.6)
		(legacy_teardrops no)
	)
	(paper "A4")
	(title_block
		(title "dpb — 14545-sa.0730WZS0815.brd")
		(comment 1 "Honey Badger (Wiwynn) / footprints 708-710 of 1066")
	)
	(layers
		(0 "F.Cu" signal "TOP")
		(4 "In1.Cu" signal "L2GND")
		(6 "In2.Cu" signal "L3")
		(8 "In3.Cu" signal "L4VCC")
		(10 "In4.Cu" signal "L5VCC")
		(12 "In5.Cu" signal "L6")
		(14 "In6.Cu" signal "L7GND")
		(2 "B.Cu" signal "BOTTOM")
		(9 "F.Adhes" user "F.Adhesive")
		(11 "B.Adhes" user "B.Adhesive")
		(13 "F.Paste" user "Package Geometry/Pastemask Top")
		(15 "B.Paste" user "Package Geometry/Pastemask Bottom")
		(5 "F.SilkS" user "Ref Des/Silkscreen Top")
		(7 "B.SilkS" user "Ref Des/Silkscreen Bottom")
		(1 "F.Mask" user "Board Geometry/Soldermask Top")
		(3 "B.Mask" user "Board Geometry/Soldermask Bottom")
		(17 "Dwgs.User" user "User.Drawings")
		(19 "Cmts.User" user "User.Comments")
		(21 "Eco1.User" user "User.Eco1")
		(23 "Eco2.User" user "User.Eco2")
		(25 "Edge.Cuts" user "Board Geometry/Outline")
		(27 "Margin" user)
		(31 "F.CrtYd" user "Package Geometry/Place Bound Top")
		(29 "B.CrtYd" user "Package Geometry/Place Bound Bottom")
		(35 "F.Fab" user "Ref Des/Assembly Top")
		(33 "B.Fab" user "Ref Des/Assembly Bottom")
	)
	(footprint ""
		(layer "F.Cu")
		(at 59.1058 -378.3838 180)
		(property "Reference" "Q59"
			(at 0 0 180)
			(layer "F.SilkS")
			(hide yes)
			(effects
				(font
					(size 1.27 1.27)
				)
			)
		)
		(property "Value" "2N7002-11-GP"
			(at 0.127 -8.9662 180)
			(unlocked yes)
			(layer "F.Fab")
			(hide yes)
			(effects
				(font
					(size 1.016 1.016)
					(thickness 0.1524)
				)
			)
		)
		(property "Device Type" "SOT23DGS2D4H44"
			(at 0.127 -10.4902 180)
			(unlocked yes)
			(layer "F.Fab")
			(hide yes)
			(effects
				(font
					(size 1.016 1.016)
					(thickness 0.1524)
				)
			)
		)
		(duplicate_pad_numbers_are_jumpers no)
		(fp_line
			(start 1.651 1.778)
			(end 1.651 -1.778)
			(stroke
				(width 0.1524)
				(type default)
			)
			(layer "F.SilkS")
		)
		(fp_line
			(start 1.651 -1.778)
			(end -1.651 -1.778)
			(stroke
				(width 0.1524)
				(type default)
			)
			(layer "F.SilkS")
		)
		(fp_line
			(start -1.651 1.778)
			(end 1.651 1.778)
			(stroke
				(width 0.1524)
				(type default)
			)
			(layer "F.SilkS")
		)
		(fp_line
			(start -1.651 -1.778)
			(end -1.651 1.778)
			(stroke
				(width 0.1524)
				(type default)
			)
			(layer "F.SilkS")
		)
		(fp_poly
			(pts
				(xy -1.778 1.8796) (xy -1.778 -1.8796) (xy 1.778 -1.8796) (xy 1.778 1.8796)
			)
			(stroke
				(width 0)
				(type default)
			)
			(fill no)
			(layer "F.CrtYd")
		)
		(fp_poly
			(pts
				(xy -1.778 1.8796) (xy -1.778 -1.8796) (xy 1.778 -1.8796) (xy 1.778 1.8796)
			)
			(stroke
				(width 0)
				(type default)
			)
			(fill no)
			(layer "F.Fab")
		)
		(pad "D" smd custom
			(at 0 -0.9525 180)
			(size 0.1905 0.1905)
			(layers "F.Cu" "F.Mask" "F.Paste")
			(net "HDD6_LED_G")
			(options
				(clearance outline)
				(anchor circle)
			)
			(primitives
				(gr_poly
					(pts
						(arc
							(start -0.1778 0.5715)
							(mid -0.321484 0.511984)
							(end -0.381 0.3683)
						)
						(arc
							(start -0.381 -0.3683)
							(mid -0.321484 -0.511984)
							(end -0.1778 -0.5715)
						)
						(arc
							(start 0.1778 -0.5715)
							(mid 0.321484 -0.511984)
							(end 0.381 -0.3683)
						)
						(arc
							(start 0.381 0.3683)
							(mid 0.321484 0.511984)
							(end 0.1778 0.5715)
						)
					)
					(width 0)
					(fill yes)
				)
			)
		)
		(pad "G" smd custom
			(at -0.98425 0.9525 180)
			(size 0.1905 0.1905)
			(layers "F.Cu" "F.Mask" "F.Paste")
			(net "HDD6_LED_B")
			(options
				(clearance outline)
				(anchor circle)
			)
			(primitives
				(gr_poly
					(pts
						(arc
							(start -0.1778 0.5715)
							(mid -0.321484 0.511984)
							(end -0.381 0.3683)
						)
						(arc
							(start -0.381 -0.3683)
							(mid -0.321484 -0.511984)
							(end -0.1778 -0.5715)
						)
						(arc
							(start 0.1778 -0.5715)
							(mid 0.321484 -0.511984)
							(end 0.381 -0.3683)
						)
						(arc
							(start 0.381 0.3683)
							(mid 0.321484 0.511984)
							(end 0.1778 0.5715)
						)
					)
					(width 0)
					(fill yes)
				)
			)
		)
		(pad "S" smd custom
			(at 0.98425 0.9525 180)
			(size 0.1905 0.1905)
			(layers "F.Cu" "F.Mask" "F.Paste")
			(net "GND")
			(options
				(clearance outline)
				(anchor circle)
			)
			(primitives
				(gr_poly
					(pts
						(arc
							(start -0.1778 0.5715)
							(mid -0.321484 0.511984)
							(end -0.381 0.3683)
						)
						(arc
							(start -0.381 -0.3683)
							(mid -0.321484 -0.511984)
							(end -0.1778 -0.5715)
						)
						(arc
							(start 0.1778 -0.5715)
							(mid 0.321484 -0.511984)
							(end 0.381 -0.3683)
						)
						(arc
							(start 0.381 0.3683)
							(mid 0.321484 0.511984)
							(end 0.1778 0.5715)
						)
					)
					(width 0)
					(fill yes)
				)
			)
		)
	)
	(footprint ""
		(layer "F.Cu")
		(at 17.500092 -129.329942 -90)
		(property "Reference" "SKT14"
			(at 0 0 270)
			(layer "F.SilkS")
			(hide yes)
			(effects
				(font
					(size 1.27 1.27)
				)
			)
		)
		(property "Value" "SKT-SATA14P-15P-12-GP"
			(at -22.6187 8.1788 270)
			(unlocked yes)
			(layer "F.Fab")
			(hide yes)
			(effects
				(font
					(size 1.016 1.016)
					(thickness 0.1524)
				)
			)
		)
		(property "Device Type" "87945-1001"
			(at -22.6187 6.6548 270)
			(unlocked yes)
			(layer "F.Fab")
			(hide yes)
			(effects
				(font
					(size 1.016 1.016)
					(thickness 0.1524)
				)
			)
		)
		(duplicate_pad_numbers_are_jumpers no)
		(fp_line
			(start -20.4724 9.652)
			(end -20.4724 2.3114)
			(stroke
				(width 0.1524)
				(type default)
			)
			(layer "F.SilkS")
		)
		(fp_line
			(start -17.8435 9.652)
			(end -20.4724 9.652)
			(stroke
				(width 0.1524)
				(type default)
			)
			(layer "F.SilkS")
		)
		(fp_line
			(start 17.8435 9.652)
			(end 17.8435 7.9502)
			(stroke
				(width 0.1524)
				(type default)
			)
			(layer "F.SilkS")
		)
		(fp_line
			(start 20.4724 9.652)
			(end 17.8435 9.652)
			(stroke
				(width 0.1524)
				(type default)
			)
			(layer "F.SilkS")
		)
		(fp_line
			(start -17.8435 7.9502)
			(end -17.8435 9.652)
			(stroke
				(width 0.1524)
				(type default)
			)
			(layer "F.SilkS")
		)
		(fp_line
			(start 17.8435 7.9502)
			(end -17.8435 7.9502)
			(stroke
				(width 0.1524)
				(type default)
			)
			(layer "F.SilkS")
		)
		(fp_line
			(start -23.7617 2.3114)
			(end -23.7617 -2.3114)
			(stroke
				(width 0.1524)
				(type default)
			)
			(layer "F.SilkS")
		)
		(fp_line
			(start -20.4724 2.3114)
			(end -23.7617 2.3114)
			(stroke
				(width 0.1524)
				(type default)
			)
			(layer "F.SilkS")
		)
		(fp_line
			(start 20.4724 2.3114)
			(end 20.4724 9.652)
			(stroke
				(width 0.1524)
				(type default)
			)
			(layer "F.SilkS")
		)
		(fp_line
			(start 23.7617 2.3114)
			(end 20.4724 2.3114)
			(stroke
				(width 0.1524)
				(type default)
			)
			(layer "F.SilkS")
		)
		(fp_line
			(start -23.117556 0.5461)
			(end -23.117556 -0.5461)
			(stroke
				(width 0.3048)
				(type default)
			)
			(layer "F.SilkS")
		)
		(fp_line
			(start 20.882356 0.5461)
			(end 20.882356 -0.5461)
			(stroke
				(width 0.3048)
				(type default)
			)
			(layer "F.SilkS")
		)
		(fp_line
			(start -20.882356 -0.5461)
			(end -20.882356 0.5461)
			(stroke
				(width 0.3048)
				(type default)
			)
			(layer "F.SilkS")
		)
		(fp_line
			(start 23.117556 -0.5461)
			(end 23.117556 0.5461)
			(stroke
				(width 0.3048)
				(type default)
			)
			(layer "F.SilkS")
		)
		(fp_line
			(start -23.7617 -2.3114)
			(end -20.4724 -2.3114)
			(stroke
				(width 0.1524)
				(type default)
			)
			(layer "F.SilkS")
		)
		(fp_line
			(start -20.4724 -2.3114)
			(end -20.4724 -5.7658)
			(stroke
				(width 0.1524)
				(type default)
			)
			(layer "F.SilkS")
		)
		(fp_line
			(start 20.4724 -2.3114)
			(end 23.7617 -2.3114)
			(stroke
				(width 0.1524)
				(type default)
			)
			(layer "F.SilkS")
		)
		(fp_line
			(start 23.7617 -2.3114)
			(end 23.7617 2.3114)
			(stroke
				(width 0.1524)
				(type default)
			)
			(layer "F.SilkS")
		)
		(fp_line
			(start -20.4724 -5.7658)
			(end 20.4724 -5.7658)
			(stroke
				(width 0.1524)
				(type default)
			)
			(layer "F.SilkS")
		)
		(fp_line
			(start 20.4724 -5.7658)
			(end 20.4724 -2.3114)
			(stroke
				(width 0.1524)
				(type default)
			)
			(layer "F.SilkS")
		)
		(fp_line
			(start -15.3924 -5.8547)
			(end -16.3576 -5.8547)
			(stroke
				(width 0.3302)
				(type default)
			)
			(layer "F.SilkS")
		)
		(fp_arc
			(start -20.882356 0.5461)
			(mid -21.999956 1.6637)
			(end -23.117556 0.5461)
			(stroke
				(width 0.3048)
				(type default)
			)
			(layer "F.SilkS")
		)
		(fp_arc
			(start 23.117556 0.5461)
			(mid 21.999956 1.6637)
			(end 20.882356 0.5461)
			(stroke
				(width 0.3048)
				(type default)
			)
			(layer "F.SilkS")
		)
		(fp_arc
			(start -23.117556 -0.5461)
			(mid -21.999956 -1.6637)
			(end -20.882356 -0.5461)
			(stroke
				(width 0.3048)
				(type default)
			)
			(layer "F.SilkS")
		)
		(fp_arc
			(start 20.882356 -0.5461)
			(mid 21.999956 -1.6637)
			(end 23.117556 -0.5461)
			(stroke
				(width 0.3048)
				(type default)
			)
			(layer "F.SilkS")
		)
		(fp_poly
			(pts
				(xy -15.87119 -5.838698) (xy -15.23619 -6.473698) (xy -16.50619 -6.473698)
			)
			(stroke
				(width 0)
				(type default)
			)
			(fill yes)
			(layer "F.SilkS")
		)
		(fp_poly
			(pts
				(xy -20.2184 -5.5118) (xy 20.2184 -5.5118) (xy 20.2184 -2.0574) (xy 23.5077 -2.0574) (xy 23.5077 2.0574)
				(xy 20.2184 2.0574) (xy 20.2184 9.398) (xy 18.0975 9.398) (xy 18.0975 7.6962) (xy -18.0975 7.6962)
				(xy -18.0975 9.398) (xy -20.2184 9.398) (xy -20.2184 2.0574) (xy -23.5077 2.0574) (xy -23.5077 -2.0574)
				(xy -20.2184 -2.0574)
			)
			(stroke
				(width 0)
				(type default)
			)
			(fill no)
			(layer "F.CrtYd")
		)
		(fp_poly
			(pts
				(xy -20.2184 -5.5118) (xy -20.2184 -6.0198) (xy -20.7264 -6.0198) (xy -20.7264 -2.5654) (xy -24.0157 -2.5654)
				(xy -24.0157 2.5654) (xy -20.7264 2.5654) (xy -20.7264 9.906) (xy -17.5895 9.906) (xy -17.5895 8.2042)
				(xy 17.5895 8.2042) (xy 17.5895 9.906) (xy 20.7264 9.906) (xy 20.7264 2.5654) (xy 24.0157 2.5654)
				(xy 24.0157 -2.5654) (xy 20.7264 -2.5654) (xy 20.7264 -6.0198) (xy -20.21586 -6.0198) (xy -20.21586 -5.5118)
				(xy 20.2184 -5.5118) (xy 20.2184 -2.0574) (xy 23.5077 -2.0574) (xy 23.5077 2.0574) (xy 20.2184 2.0574)
				(xy 20.2184 9.398) (xy 18.0975 9.398) (xy 18.0975 7.6962) (xy -18.0975 7.6962) (xy -18.0975 9.398)
				(xy -20.2184 9.398) (xy -20.2184 2.0574) (xy -23.5077 2.0574) (xy -23.5077 -2.0574) (xy -20.2184 -2.0574)
			)
			(stroke
				(width 0)
				(type default)
			)
			(fill no)
			(layer "F.CrtYd")
		)
		(fp_poly
			(pts
				(xy -20.7264 -6.0198) (xy -20.7264 -2.5654) (xy -24.0157 -2.5654) (xy -24.0157 2.5654) (xy -20.7264 2.5654)
				(xy -20.7264 9.906) (xy -17.5895 9.906) (xy -17.5895 8.2042) (xy 17.5895 8.2042) (xy 17.5895 9.906)
				(xy 20.7264 9.906) (xy 20.7264 2.5654) (xy 24.0157 2.5654) (xy 24.0157 -2.5654) (xy 20.7264 -2.5654)
				(xy 20.7264 -6.0198)
			)
			(stroke
				(width 0)
				(type default)
			)
			(fill no)
			(layer "F.Fab")
		)
		(pad "" np_thru_hole circle
			(at -18.999962 -2.350008 270)
			(size 0.254 0.254)
			(drill 1.8542)
			(layers "*.Cu" "*.Mask")
			(clearance 1.1557)
			(thermal_gap 1.1557)
		)
		(pad "" np_thru_hole circle
			(at 18.999962 -2.350008 270)
			(size 0.254 0.254)
			(drill 1.8542)
			(layers "*.Cu" "*.Mask")
			(clearance 1.1557)
			(thermal_gap 1.1557)
		)
		(pad "H1" thru_hole oval
			(at -21.999956 0 270)
			(size 1.524 2.6162)
			(drill oval 0.8128 1.905)
			(layers "*.Cu" "*.Mask")
			(remove_unused_layers no)
			(net "GND")
			(clearance 0.1524)
			(thermal_gap 0.1524)
		)
		(pad "H2" thru_hole oval
			(at 21.999956 0 270)
			(size 1.524 2.6162)
			(drill oval 0.8128 1.905)
			(layers "*.Cu" "*.Mask")
			(remove_unused_layers no)
			(net "GND")
			(clearance 0.1524)
			(thermal_gap 0.1524)
		)
		(pad "P1" smd rect
			(at -1.89992 -4.249928 270)
			(size 0.6604 2.3876)
			(layers "F.Cu" "F.Mask" "F.Paste")
			(net "Net_50")
		)
		(pad "P2" smd rect
			(at -0.62992 -4.249928 270)
			(size 0.6604 2.3876)
			(layers "F.Cu" "F.Mask" "F.Paste")
			(net "Net_49")
		)
		(pad "P3" smd rect
			(at 0.64008 -4.249928 270)
			(size 0.6604 2.3876)
			(layers "F.Cu" "F.Mask" "F.Paste")
			(net "Net_48")
		)
		(pad "P4" smd rect
			(at 1.91008 -4.249928 270)
			(size 0.6604 2.3876)
			(layers "F.Cu" "F.Mask" "F.Paste")
			(net "GND")
		)
		(pad "P5" smd rect
			(at 3.18008 -4.249928 270)
			(size 0.6604 2.3876)
			(layers "F.Cu" "F.Mask" "F.Paste")
			(net "HDD_PRSNT_NET13")
		)
		(pad "P6" smd rect
			(at 4.45008 -4.249928 270)
			(size 0.6604 2.3876)
			(layers "F.Cu" "F.Mask" "F.Paste")
			(net "GND")
		)
		(pad "P7" smd rect
			(at 5.72008 -4.249928 270)
			(size 0.6604 2.3876)
			(layers "F.Cu" "F.Mask" "F.Paste")
			(net "5V_PRE_13")
		)
		(pad "P8" smd rect
			(at 6.99008 -4.249928 270)
			(size 0.6604 2.3876)
			(layers "F.Cu" "F.Mask" "F.Paste")
			(net "P5V_HDD13")
		)
		(pad "P9" smd rect
			(at 8.26008 -4.249928 270)
			(size 0.6604 2.3876)
			(layers "F.Cu" "F.Mask" "F.Paste")
			(net "P5V_HDD13")
		)
		(pad "P10" smd rect
			(at 9.53008 -4.249928 270)
			(size 0.6604 2.3876)
			(layers "F.Cu" "F.Mask" "F.Paste")
			(net "GND")
		)
		(pad "P11" smd rect
			(at 10.80008 -4.249928 270)
			(size 0.6604 2.3876)
			(layers "F.Cu" "F.Mask" "F.Paste")
			(net "ACT_HDD13")
		)
		(pad "P12" smd rect
			(at 12.07008 -4.249928 270)
			(size 0.6604 2.3876)
			(layers "F.Cu" "F.Mask" "F.Paste")
			(net "GND")
		)
		(pad "P13" smd rect
			(at 13.34008 -4.249928 270)
			(size 0.6604 2.3876)
			(layers "F.Cu" "F.Mask" "F.Paste")
			(net "12V_PRE_13")
		)
		(pad "P14" smd rect
			(at 14.61008 -4.249928 270)
			(size 0.6604 2.3876)
			(layers "F.Cu" "F.Mask" "F.Paste")
			(net "P12V_HDD13")
		)
		(pad "P15" smd rect
			(at 15.88008 -4.249928 270)
			(size 0.6604 2.3876)
			(layers "F.Cu" "F.Mask" "F.Paste")
			(net "P12V_HDD13")
		)
		(pad "S1" smd rect
			(at -15.86992 -4.249928 270)
			(size 0.6604 2.3876)
			(layers "F.Cu" "F.Mask" "F.Paste")
			(net "GND")
		)
		(pad "S2" smd rect
			(at -14.59992 -4.249928 270)
			(size 0.6604 2.3876)
			(layers "F.Cu" "F.Mask" "F.Paste")
			(net "SAS2X28_A_HDD13_TX_+")
		)
		(pad "S3" smd rect
			(at -13.32992 -4.249928 270)
			(size 0.6604 2.3876)
			(layers "F.Cu" "F.Mask" "F.Paste")
			(net "SAS2X28_A_HDD13_TX_-")
		)
		(pad "S4" smd rect
			(at -12.05992 -4.249928 270)
			(size 0.6604 2.3876)
			(layers "F.Cu" "F.Mask" "F.Paste")
			(net "GND")
		)
		(pad "S5" smd rect
			(at -10.78992 -4.249928 270)
			(size 0.6604 2.3876)
			(layers "F.Cu" "F.Mask" "F.Paste")
			(net "SAS2X28_DRIVE_RX_N_A13")
		)
		(pad "S6" smd rect
			(at -9.51992 -4.249928 270)
			(size 0.6604 2.3876)
			(layers "F.Cu" "F.Mask" "F.Paste")
			(net "SAS2X28_DRIVE_RX_P_A13")
		)
		(pad "S7" smd rect
			(at -8.24992 -4.249928 270)
			(size 0.6604 2.3876)
			(layers "F.Cu" "F.Mask" "F.Paste")
			(net "GND")
		)
		(pad "S8" smd rect
			(at -7.480046 -2.100072 270)
			(size 0.508 1.905)
			(layers "F.Cu" "F.Mask" "F.Paste")
			(net "GND")
		)
		(pad "S9" smd rect
			(at -6.679946 -2.100072 270)
			(size 0.508 1.905)
			(layers "F.Cu" "F.Mask" "F.Paste")
			(net "SAS2X28_B_HDD13_TX_+")
		)
		(pad "S10" smd rect
			(at -5.8801 -2.100072 270)
			(size 0.508 1.905)
			(layers "F.Cu" "F.Mask" "F.Paste")
			(net "SAS2X28_B_HDD13_TX_-")
		)
		(pad "S11" smd rect
			(at -5.08 -2.100072 270)
			(size 0.508 1.905)
			(layers "F.Cu" "F.Mask" "F.Paste")
			(net "GND")
		)
		(pad "S12" smd rect
			(at -4.2799 -2.100072 270)
			(size 0.508 1.905)
			(layers "F.Cu" "F.Mask" "F.Paste")
			(net "SAS2X28_DRIVE_RX_N_B13")
		)
		(pad "S13" smd rect
			(at -3.480054 -2.100072 270)
			(size 0.508 1.905)
			(layers "F.Cu" "F.Mask" "F.Paste")
			(net "SAS2X28_DRIVE_RX_P_B13")
		)
		(pad "S14" smd rect
			(at -2.679954 -2.100072 270)
			(size 0.508 1.905)
			(layers "F.Cu" "F.Mask" "F.Paste")
			(net "GND")
		)
		(zone
			(layers "F.Cu" "B.Cu" "In1.Cu" "In2.Cu" "In3.Cu" "In4.Cu" "In5.Cu" "In6.Cu")
			(hatch none 0.5)
			(connect_pads
				(clearance 0)
			)
			(min_thickness 0.25)
			(keepout
				(tracks not_allowed)
				(vias allowed)
				(pads allowed)
				(copperpour not_allowed)
				(footprints allowed)
			)
			(placement
				(enabled no)
				(sheetname "")
			)
			(fill
				(thermal_gap 0.5)
				(thermal_bridge_width 0.5)
				(island_removal_mode 0)
			)
			(polygon
				(pts
					(arc
						(start 21.082 -148.329904)
						(mid 18.6182 -148.329904)
						(end 21.082 -148.329904)
					)
				)
			)
		)
		(zone
			(layers "F.Cu" "B.Cu" "In1.Cu" "In2.Cu" "In3.Cu" "In4.Cu" "In5.Cu" "In6.Cu")
			(hatch none 0.5)
			(connect_pads
				(clearance 0)
			)
			(min_thickness 0.25)
			(keepout
				(tracks not_allowed)
				(vias allowed)
				(pads allowed)
				(copperpour not_allowed)
				(footprints allowed)
			)
			(placement
				(enabled no)
				(sheetname "")
			)
			(fill
				(thermal_gap 0.5)
				(thermal_bridge_width 0.5)
				(island_removal_mode 0)
			)
			(polygon
				(pts
					(arc
						(start 21.082 -110.32998)
						(mid 18.6182 -110.32998)
						(end 21.082 -110.32998)
					)
				)
			)
		)
	)
	(footprint ""
		(layer "F.Cu")
		(at 4.445 -283.718 90)
		(property "Reference" "PC68"
			(at 0 0 90)
			(layer "F.SilkS")
			(hide yes)
			(effects
				(font
					(size 1.27 1.27)
				)
			)
		)
		(property "Value" "SC22U25V5MX-GP"
			(at -0.0762 -6.1214 90)
			(unlocked yes)
			(layer "F.Fab")
			(hide yes)
			(effects
				(font
					(size 1.016 1.016)
					(thickness 0.1524)
				)
			)
		)
		(property "Device Type" "C805H58"
			(at -0.0762 -8.1534 90)
			(unlocked yes)
			(layer "F.Fab")
			(hide yes)
			(effects
				(font
					(size 1.016 1.016)
					(thickness 0.1524)
				)
			)
		)
		(duplicate_pad_numbers_are_jumpers no)
		(fp_line
			(start 0.635 0)
			(end -0.635 0)
			(stroke
				(width 0.508)
				(type default)
			)
			(layer "F.SilkS")
		)
		(fp_rect
			(start -0.9652 1.778)
			(end 0.9652 -1.778)
			(stroke
				(width 0)
				(type default)
			)
			(fill no)
			(layer "F.CrtYd")
		)
		(fp_poly
			(pts
				(xy -0.9652 -1.778) (xy 0.9652 -1.778) (xy 0.9652 1.778) (xy -0.9652 1.778)
			)
			(stroke
				(width 0)
				(type default)
			)
			(fill no)
			(layer "F.Fab")
		)
		(pad "1" smd rect
			(at 0 -0.9652 90)
			(size 1.397 1.143)
			(layers "F.Cu" "F.Mask" "F.Paste")
			(net "P12V")
		)
		(pad "2" smd rect
			(at 0 0.9652 90)
			(size 1.397 1.143)
			(layers "F.Cu" "F.Mask" "F.Paste")
			(net "GND")
		)
	)
)
